# BASEBOARD_FAB2 (Tioga Pass) — schematic netlist excerpt (pin names and nets, part order shuffled) for the footprints in the layout excerpt that follows; sources: Cadence DE-HDL packaged netlist, KiCad conversion of Wiwynn_Tioga_Pass_MB.brd

C25W33  CAP  1.0UF 16V 10% X6S  pkg 0402  page 149 : A = VCC_ADCAV3V3 ; B = GND

U9P1  TPS3700  IC  pkg SM  page 200
  OUTB  = A_P12V_STBY_FPH_GATE
  VDD  = P12V_STBY
  INBN  = A_P12V_STBY_FP_TRIGGER
  INAP  = A_P12V_STBY_ADR_TRIGGER
  GND  = GND
  OUTA  = FM_UV_ADR_TRIGGER_N

C5M13  CAP_A  47UF 4V 20% X5R  pkg 0603V  page 222 : A = PVTT_DEF ; B = GND

(kicad_pcb
	(version 20260206)
	(generator "pcbnew")
	(generator_version "10.0")
	(general
		(thickness 1.6)
		(legacy_teardrops no)
	)
	(paper "A4")
	(title_block
		(title "Wiwynn_Tioga_Pass_MB.brd")
		(comment 1 "Tioga Pass / footprints 2519-2521 of 4770")
	)
	(layers
		(0 "F.Cu" signal "TOP")
		(4 "In1.Cu" signal "L2GND")
		(6 "In2.Cu" signal "L3")
		(8 "In3.Cu" signal "L4GND")
		(10 "In4.Cu" signal "L5")
		(12 "In5.Cu" signal "L6GND")
		(14 "In6.Cu" signal "L7VCC")
		(16 "In7.Cu" signal "L8VCC")
		(18 "In8.Cu" signal "L9GND")
		(20 "In9.Cu" signal "L10")
		(22 "In10.Cu" signal "L11GND")
		(24 "In11.Cu" signal "L12")
		(26 "In12.Cu" signal "L13GND")
		(2 "B.Cu" signal "BOTTOM")
		(9 "F.Adhes" user "F.Adhesive")
		(11 "B.Adhes" user "B.Adhesive")
		(13 "F.Paste" user "Package Geometry/Pastemask Top")
		(15 "B.Paste" user "Package Geometry/Pastemask Bottom")
		(5 "F.SilkS" user "Ref Des/Silkscreen Top")
		(7 "B.SilkS" user "Ref Des/Silkscreen Bottom")
		(1 "F.Mask" user "Board Geometry/Soldermask Top")
		(3 "B.Mask" user "Board Geometry/Soldermask Bottom")
		(17 "Dwgs.User" user "User.Drawings")
		(19 "Cmts.User" user "User.Comments")
		(21 "Eco1.User" user "User.Eco1")
		(23 "Eco2.User" user "User.Eco2")
		(25 "Edge.Cuts" user "Board Geometry/Outline")
		(27 "Margin" user)
		(31 "F.CrtYd" user "Package Geometry/Place Bound Top")
		(29 "B.CrtYd" user "Package Geometry/Place Bound Bottom")
		(35 "F.Fab" user "Ref Des/Assembly Top")
		(33 "B.Fab" user "Ref Des/Assembly Bottom")
	)
	(footprint ""
		(layer "B.Cu")
		(at 259.9182 -126.1364 -90)
		(property "Reference" "C5M13"
			(at 0 0 90)
			(layer "B.SilkS")
			(hide yes)
			(effects
				(font
					(size 1.27 1.27)
				)
				(justify mirror)
			)
		)
		(property "Value" ""
			(at 0 0 90)
			(layer "B.Fab")
			(effects
				(font
					(size 1.27 1.27)
				)
				(justify mirror)
			)
		)
		(duplicate_pad_numbers_are_jumpers no)
		(fp_rect
			(start 0.500126 1.598422)
			(end -0.500126 -0.201422)
			(stroke
				(width 0)
				(type default)
			)
			(fill no)
			(layer "B.CrtYd")
		)
		(fp_line
			(start -0.500126 1.598422)
			(end 0.500126 1.598422)
			(stroke
				(width 0.1)
				(type default)
			)
			(layer "B.Fab")
		)
		(fp_line
			(start 0.500126 1.598422)
			(end 0.500126 -0.201422)
			(stroke
				(width 0.1)
				(type default)
			)
			(layer "B.Fab")
		)
		(fp_line
			(start -0.500126 -0.201422)
			(end -0.500126 1.598422)
			(stroke
				(width 0.1)
				(type default)
			)
			(layer "B.Fab")
		)
		(fp_line
			(start 0.500126 -0.201422)
			(end -0.500126 -0.201422)
			(stroke
				(width 0.1)
				(type default)
			)
			(layer "B.Fab")
		)
		(pad "1" smd rect
			(at 0 0 180)
			(size 0.889 0.9906)
			(layers "B.Cu" "B.Mask" "B.Paste")
			(net "PVTT_DEF")
		)
		(pad "2" smd rect
			(at 0 1.397 180)
			(size 0.889 0.9906)
			(layers "B.Cu" "B.Mask" "B.Paste")
			(net "GND")
		)
		(zone
			(layer "B.Cu")
			(hatch none 0.5)
			(connect_pads
				(clearance 0)
			)
			(min_thickness 0.25)
			(keepout
				(tracks allowed)
				(vias not_allowed)
				(pads allowed)
				(copperpour not_allowed)
				(footprints allowed)
			)
			(placement
				(enabled no)
				(sheetname "")
			)
			(fill
				(thermal_gap 0.5)
				(thermal_bridge_width 0.5)
				(island_removal_mode 0)
			)
			(polygon
				(pts
					(xy 258.9657 -125.6411) (xy 259.4737 -125.6411) (xy 259.4737 -126.6317) (xy 258.9657 -126.6317)
				)
			)
		)
		(zone
			(layer "B.Cu")
			(hatch none 0.5)
			(connect_pads
				(clearance 0)
			)
			(min_thickness 0.25)
			(keepout
				(tracks not_allowed)
				(vias allowed)
				(pads allowed)
				(copperpour not_allowed)
				(footprints allowed)
			)
			(placement
				(enabled no)
				(sheetname "")
			)
			(fill
				(thermal_gap 0.5)
				(thermal_bridge_width 0.5)
				(island_removal_mode 0)
			)
			(polygon
				(pts
					(xy 258.9657 -125.6411) (xy 259.4737 -125.6411) (xy 259.4737 -126.6317) (xy 258.9657 -126.6317)
				)
			)
		)
	)
	(footprint ""
		(layer "B.Cu")
		(at 413.0675 -25.273 -90)
		(property "Reference" "C25W33"
			(at 0.8382 -0.67818 270)
			(unlocked yes)
			(layer "B.SilkS")
			(effects
				(font
					(size 0.4064 0.254)
					(thickness 0.1524)
				)
				(justify left mirror)
			)
		)
		(property "Value" ""
			(at 0 0 90)
			(layer "B.Fab")
			(effects
				(font
					(size 1.27 1.27)
				)
				(justify mirror)
			)
		)
		(duplicate_pad_numbers_are_jumpers no)
		(fp_poly
			(pts
				(xy -0.3048 -0.1016) (xy -0.3048 0.9906) (xy 0.3048 0.9906) (xy 0.3048 -0.1016)
			)
			(stroke
				(width 0)
				(type default)
			)
			(fill no)
			(layer "B.CrtYd")
		)
		(fp_line
			(start -0.3048 0.9906)
			(end -0.3048 -0.1016)
			(stroke
				(width 0.1)
				(type default)
			)
			(layer "B.Fab")
		)
		(fp_line
			(start 0.3048 0.9906)
			(end -0.3048 0.9906)
			(stroke
				(width 0.1)
				(type default)
			)
			(layer "B.Fab")
		)
		(fp_line
			(start -0.3048 -0.1016)
			(end 0.3048 -0.1016)
			(stroke
				(width 0.1)
				(type default)
			)
			(layer "B.Fab")
		)
		(fp_line
			(start 0.3048 -0.1016)
			(end 0.3048 0.9906)
			(stroke
				(width 0.1)
				(type default)
			)
			(layer "B.Fab")
		)
		(pad "1" smd rect
			(at 0 0 90)
			(size 0.508 0.508)
			(layers "B.Cu" "B.Mask" "B.Paste")
			(net "VCC_ADCAV3V3")
		)
		(pad "2" smd rect
			(at 0 0.889 90)
			(size 0.508 0.508)
			(layers "B.Cu" "B.Mask" "B.Paste")
			(net "GND")
		)
		(zone
			(layer "B.Cu")
			(hatch none 0.5)
			(connect_pads
				(clearance 0)
			)
			(min_thickness 0.25)
			(keepout
				(tracks not_allowed)
				(vias allowed)
				(pads allowed)
				(copperpour not_allowed)
				(footprints allowed)
			)
			(placement
				(enabled no)
				(sheetname "")
			)
			(fill
				(thermal_gap 0.5)
				(thermal_bridge_width 0.5)
				(island_removal_mode 0)
			)
			(polygon
				(pts
					(xy 412.4325 -25.019) (xy 412.4325 -25.527) (xy 412.8135 -25.527) (xy 412.8135 -25.019)
				)
			)
		)
		(zone
			(layer "B.Cu")
			(hatch none 0.5)
			(connect_pads
				(clearance 0)
			)
			(min_thickness 0.25)
			(keepout
				(tracks allowed)
				(vias not_allowed)
				(pads allowed)
				(copperpour not_allowed)
				(footprints allowed)
			)
			(placement
				(enabled no)
				(sheetname "")
			)
			(fill
				(thermal_gap 0.5)
				(thermal_bridge_width 0.5)
				(island_removal_mode 0)
			)
			(polygon
				(pts
					(xy 412.8135 -25.019) (xy 412.8135 -25.527) (xy 412.4325 -25.527) (xy 412.4325 -25.019)
				)
			)
		)
	)
	(footprint ""
		(layer "B.Cu")
		(at 22.0345 -83.312 -90)
		(property "Reference" "U9P1"
			(at -1.05918 -0.62357 270)
			(unlocked yes)
			(layer "B.SilkS")
			(effects
				(font
					(size 0.7874 0.5842)
					(thickness 0.1524)
				)
				(justify mirror)
			)
		)
		(property "Value" ""
			(at 0 0 90)
			(layer "B.Fab")
			(effects
				(font
					(size 1.27 1.27)
				)
				(justify mirror)
			)
		)
		(duplicate_pad_numbers_are_jumpers no)
		(fp_circle
			(center 1.0795 -0.054102)
			(end 1.0795 -0.181102)
			(stroke
				(width 0.254)
				(type default)
			)
			(fill no)
			(layer "B.SilkS")
		)
		(fp_rect
			(start 0.216154 1.27508)
			(end -1.333754 -0.275082)
			(stroke
				(width 0)
				(type default)
			)
			(fill no)
			(layer "B.CrtYd")
		)
		(fp_line
			(start -1.333754 1.27508)
			(end 0.216154 1.27508)
			(stroke
				(width 0.1)
				(type default)
			)
			(layer "B.Fab")
		)
		(fp_line
			(start 0.216154 1.27508)
			(end 0.216154 -0.275082)
			(stroke
				(width 0.1)
				(type default)
			)
			(layer "B.Fab")
		)
		(fp_line
			(start -1.333754 -0.275082)
			(end -1.333754 1.27508)
			(stroke
				(width 0.1)
				(type default)
			)
			(layer "B.Fab")
		)
		(fp_line
			(start 0.216154 -0.275082)
			(end -1.333754 -0.275082)
			(stroke
				(width 0.1)
				(type default)
			)
			(layer "B.Fab")
		)
		(fp_circle
			(center 1.0795 -0.054102)
			(end 1.0795 -0.181102)
			(stroke
				(width 0.254)
				(type default)
			)
			(fill no)
			(layer "B.Fab")
		)
		(pad "1" smd rect
			(at 0 0 90)
			(size 0.9398 0.3048)
			(layers "B.Cu" "B.Mask" "B.Paste")
			(net "A_P12V_STBY_FPH_GATE")
		)
		(pad "2" smd rect
			(at 0.0254 0.500126 90)
			(size 0.889 0.3048)
			(layers "B.Cu" "B.Mask" "B.Paste")
			(net "P12V_STBY")
		)
		(pad "3" smd rect
			(at 0.0254 0.999998 90)
			(size 0.889 0.3048)
			(layers "B.Cu" "B.Mask" "B.Paste")
			(net "A_P12V_STBY_FP_TRIGGER")
		)
		(pad "4" smd rect
			(at -1.143 0.999998 90)
			(size 0.889 0.3048)
			(layers "B.Cu" "B.Mask" "B.Paste")
			(net "A_P12V_STBY_ADR_TRIGGER")
		)
		(pad "5" smd rect
			(at -1.143 0.500126 90)
			(size 0.889 0.3048)
			(layers "B.Cu" "B.Mask" "B.Paste")
			(net "GND")
		)
		(pad "6" smd rect
			(at -1.143 0 90)
			(size 0.889 0.3048)
			(layers "B.Cu" "B.Mask" "B.Paste")
			(net "FM_UV_ADR_TRIGGER_N")
		)
	)
)
